# T6G (Grand Teton) — schematic netlist excerpt (pin names and nets, part order shuffled) for the footprints in the layout excerpt that follows; sources: Cadence DE-HDL packaged netlist, KiCad conversion of 04192023_DAF0TMB3IC0_F0TG_MB_C_brd_V02_OCP.brd

C1044  Q_CAP  10UF 6.3V 20% X6S  pkg C0402  page 312 : A = P0V9_CPU0_RT_2D ; B = GND
R242  Q_RES  0 5% CHIP  pkg 0402LF  page 81 : A = PWRGD_CPU0_PWROK ; B = FM_PWRGD_CPU0_PWROK

(kicad_pcb
	(version 20260206)
	(generator "pcbnew")
	(generator_version "10.0")
	(general
		(thickness 1.6)
		(legacy_teardrops no)
	)
	(paper "A4")
	(title_block
		(title "04192023_DAF0TMB3IC0_F0TG_MB_C_brd_V02_OCP.brd")
		(comment 1 "Grand Teton / footprints 6957-6958 of 8354")
	)
	(layers
		(0 "F.Cu" signal "TOP")
		(4 "In1.Cu" signal "GND")
		(6 "In2.Cu" signal "IN1")
		(8 "In3.Cu" signal "GND1")
		(10 "In4.Cu" signal "IN2")
		(12 "In5.Cu" signal "GND2")
		(14 "In6.Cu" signal "IN3")
		(16 "In7.Cu" signal "GND3")
		(18 "In8.Cu" signal "VCC")
		(20 "In9.Cu" signal "VCC1")
		(22 "In10.Cu" signal "GND4")
		(24 "In11.Cu" signal "IN4")
		(26 "In12.Cu" signal "GND5")
		(28 "In13.Cu" signal "IN5")
		(30 "In14.Cu" signal "GND6")
		(32 "In15.Cu" signal "IN6")
		(34 "In16.Cu" signal "GND7")
		(2 "B.Cu" signal "BOTTOM")
		(9 "F.Adhes" user "F.Adhesive")
		(11 "B.Adhes" user "B.Adhesive")
		(13 "F.Paste" user "Package Geometry/Pastemask Top")
		(15 "B.Paste" user "Package Geometry/Pastemask Bottom")
		(5 "F.SilkS" user "Ref Des/Silkscreen Top")
		(7 "B.SilkS" user "Ref Des/Silkscreen Bottom")
		(1 "F.Mask" user "Board Geometry/Soldermask Top")
		(3 "B.Mask" user "Board Geometry/Soldermask Bottom")
		(17 "Dwgs.User" user "User.Drawings")
		(19 "Cmts.User" user "User.Comments")
		(21 "Eco1.User" user "User.Eco1")
		(23 "Eco2.User" user "User.Eco2")
		(25 "Edge.Cuts" user "Board Geometry/Outline")
		(27 "Margin" user)
		(31 "F.CrtYd" user "Package Geometry/Place Bound Top")
		(29 "B.CrtYd" user "Package Geometry/Place Bound Bottom")
		(35 "F.Fab" user "Ref Des/Assembly Top")
		(33 "B.Fab" user "Ref Des/Assembly Bottom")
	)
	(footprint ""
		(layer "B.Cu")
		(at 377.691142 -398.942052 90)
		(property "Reference" "C1044"
			(at 0 0 90)
			(layer "B.SilkS")
			(hide yes)
			(effects
				(font
					(size 1.27 1.27)
				)
				(justify mirror)
			)
		)
		(property "Value" ""
			(at 0 0 90)
			(layer "B.Fab")
			(effects
				(font
					(size 1.27 1.27)
				)
				(justify mirror)
			)
		)
		(duplicate_pad_numbers_are_jumpers no)
		(fp_line
			(start 0.7874 -0.4064)
			(end -0.7874 -0.4064)
			(stroke
				(width 0.1524)
				(type default)
			)
			(layer "B.SilkS")
		)
		(fp_line
			(start -0.7874 -0.4064)
			(end -0.7874 0.4064)
			(stroke
				(width 0.1524)
				(type default)
			)
			(layer "B.SilkS")
		)
		(fp_line
			(start 0.7874 0.4064)
			(end 0.7874 -0.4064)
			(stroke
				(width 0.1524)
				(type default)
			)
			(layer "B.SilkS")
		)
		(fp_line
			(start -0.7874 0.4064)
			(end 0.7874 0.4064)
			(stroke
				(width 0.1524)
				(type default)
			)
			(layer "B.SilkS")
		)
		(fp_line
			(start 0.67945 -0.305054)
			(end 0.12065 -0.305054)
			(stroke
				(width 0.1)
				(type default)
			)
			(layer "B.Fab")
		)
		(fp_line
			(start 0.12065 -0.305054)
			(end 0.12065 -0.2794)
			(stroke
				(width 0.1)
				(type default)
			)
			(layer "B.Fab")
		)
		(fp_line
			(start -0.12065 -0.3048)
			(end -0.67945 -0.3048)
			(stroke
				(width 0.1)
				(type default)
			)
			(layer "B.Fab")
		)
		(fp_line
			(start -0.67945 -0.3048)
			(end -0.67945 0.3048)
			(stroke
				(width 0.1)
				(type default)
			)
			(layer "B.Fab")
		)
		(fp_line
			(start 0.12065 -0.2794)
			(end -0.12065 -0.2794)
			(stroke
				(width 0.1)
				(type default)
			)
			(layer "B.Fab")
		)
		(fp_line
			(start -0.12065 -0.2794)
			(end -0.12065 -0.3048)
			(stroke
				(width 0.1)
				(type default)
			)
			(layer "B.Fab")
		)
		(fp_line
			(start 0.12065 0.2794)
			(end 0.12065 0.3048)
			(stroke
				(width 0.1)
				(type default)
			)
			(layer "B.Fab")
		)
		(fp_line
			(start -0.120396 0.2794)
			(end 0.12065 0.2794)
			(stroke
				(width 0.1)
				(type default)
			)
			(layer "B.Fab")
		)
		(fp_line
			(start 0.67945 0.3048)
			(end 0.67945 -0.305054)
			(stroke
				(width 0.1)
				(type default)
			)
			(layer "B.Fab")
		)
		(fp_line
			(start 0.12065 0.3048)
			(end 0.67945 0.3048)
			(stroke
				(width 0.1)
				(type default)
			)
			(layer "B.Fab")
		)
		(fp_line
			(start -0.120396 0.3048)
			(end -0.120396 0.2794)
			(stroke
				(width 0.1)
				(type default)
			)
			(layer "B.Fab")
		)
		(fp_line
			(start -0.67945 0.3048)
			(end -0.120396 0.3048)
			(stroke
				(width 0.1)
				(type default)
			)
			(layer "B.Fab")
		)
		(pad "1" smd circle
			(at 0.40005 0 270)
			(size 0 0)
			(layers "B.Cu" "B.Mask" "B.Paste")
			(net "P0V9_CPU0_RT_2D")
		)
		(pad "2" smd circle
			(at -0.40005 0 270)
			(size 0 0)
			(layers "B.Cu" "B.Mask" "B.Paste")
			(net "GND")
		)
	)
	(footprint ""
		(layer "B.Cu")
		(at 179.997608 -126.833376 90)
		(property "Reference" "R242"
			(at 0 0 90)
			(layer "B.SilkS")
			(hide yes)
			(effects
				(font
					(size 1.27 1.27)
				)
				(justify mirror)
			)
		)
		(property "Value" ""
			(at 0 0 90)
			(layer "B.Fab")
			(effects
				(font
					(size 1.27 1.27)
				)
				(justify mirror)
			)
		)
		(duplicate_pad_numbers_are_jumpers no)
		(fp_line
			(start 0.7874 -0.4064)
			(end -0.7874 -0.4064)
			(stroke
				(width 0.1524)
				(type default)
			)
			(layer "B.SilkS")
		)
		(fp_line
			(start -0.7874 -0.4064)
			(end -0.7874 0.4064)
			(stroke
				(width 0.1524)
				(type default)
			)
			(layer "B.SilkS")
		)
		(fp_line
			(start 0.7874 0.4064)
			(end 0.7874 -0.4064)
			(stroke
				(width 0.1524)
				(type default)
			)
			(layer "B.SilkS")
		)
		(fp_line
			(start -0.7874 0.4064)
			(end 0.7874 0.4064)
			(stroke
				(width 0.1524)
				(type default)
			)
			(layer "B.SilkS")
		)
		(fp_line
			(start 0.67945 -0.305054)
			(end 0.12065 -0.305054)
			(stroke
				(width 0.1)
				(type default)
			)
			(layer "B.Fab")
		)
		(fp_line
			(start 0.12065 -0.305054)
			(end 0.12065 -0.2794)
			(stroke
				(width 0.1)
				(type default)
			)
			(layer "B.Fab")
		)
		(fp_line
			(start -0.12065 -0.3048)
			(end -0.67945 -0.3048)
			(stroke
				(width 0.1)
				(type default)
			)
			(layer "B.Fab")
		)
		(fp_line
			(start -0.67945 -0.3048)
			(end -0.67945 0.3048)
			(stroke
				(width 0.1)
				(type default)
			)
			(layer "B.Fab")
		)
		(fp_line
			(start 0.12065 -0.2794)
			(end -0.12065 -0.2794)
			(stroke
				(width 0.1)
				(type default)
			)
			(layer "B.Fab")
		)
		(fp_line
			(start -0.12065 -0.2794)
			(end -0.12065 -0.3048)
			(stroke
				(width 0.1)
				(type default)
			)
			(layer "B.Fab")
		)
		(fp_line
			(start 0.12065 0.2794)
			(end 0.12065 0.3048)
			(stroke
				(width 0.1)
				(type default)
			)
			(layer "B.Fab")
		)
		(fp_line
			(start -0.120396 0.2794)
			(end 0.12065 0.2794)
			(stroke
				(width 0.1)
				(type default)
			)
			(layer "B.Fab")
		)
		(fp_line
			(start 0.67945 0.3048)
			(end 0.67945 -0.305054)
			(stroke
				(width 0.1)
				(type default)
			)
			(layer "B.Fab")
		)
		(fp_line
			(start 0.12065 0.3048)
			(end 0.67945 0.3048)
			(stroke
				(width 0.1)
				(type default)
			)
			(layer "B.Fab")
		)
		(fp_line
			(start -0.120396 0.3048)
			(end -0.120396 0.2794)
			(stroke
				(width 0.1)
				(type default)
			)
			(layer "B.Fab")
		)
		(fp_line
			(start -0.67945 0.3048)
			(end -0.120396 0.3048)
			(stroke
				(width 0.1)
				(type default)
			)
			(layer "B.Fab")
		)
		(pad "1" smd circle
			(at 0.40005 0 270)
			(size 0 0)
			(layers "B.Cu" "B.Mask" "B.Paste")
			(net "PWRGD_CPU0_PWROK")
		)
		(pad "2" smd circle
			(at -0.40005 0 270)
			(size 0 0)
			(layers "B.Cu" "B.Mask" "B.Paste")
			(net "FM_PWRGD_CPU0_PWROK")
		)
	)
)
